(kicad_pcb
	(version 20241229)
	(generator "pcbnew")
	(generator_version "9.0")
	(general
		(thickness 1.6642)
		(legacy_teardrops no)
	)
	(paper "A3")
	(title_block
		(title "PolarFire SoM")
		(date "2025-07-22")
		(rev "1.1.4")
		(company "Antmicro Ltd")
		(comment 1 "www.antmicro.com")
		(comment 9 "footprints 301-304 of 470")
	)
	(layers
		(0 "F.Cu" mixed)
		(4 "In1.Cu" power)
		(6 "In2.Cu" signal)
		(8 "In3.Cu" power)
		(10 "In4.Cu" signal)
		(12 "In5.Cu" power)
		(14 "In6.Cu" power)
		(16 "In7.Cu" signal)
		(18 "In8.Cu" power)
		(20 "In9.Cu" signal)
		(22 "In10.Cu" power)
		(24 "In11.Cu" signal)
		(26 "In12.Cu" signal)
		(2 "B.Cu" mixed)
		(9 "F.Adhes" user "F.Adhesive")
		(11 "B.Adhes" user "B.Adhesive")
		(13 "F.Paste" user)
		(15 "B.Paste" user)
		(5 "F.SilkS" user "F.Silkscreen")
		(7 "B.SilkS" user "B.Silkscreen")
		(1 "F.Mask" user)
		(3 "B.Mask" user)
		(17 "Dwgs.User" user "User.Drawings")
		(19 "Cmts.User" user "User.Comments")
		(21 "Eco1.User" user "User.Eco1")
		(23 "Eco2.User" user "User.Eco2")
		(25 "Edge.Cuts" user)
		(27 "Margin" user)
		(31 "F.CrtYd" user "F.Courtyard")
		(29 "B.CrtYd" user "B.Courtyard")
		(35 "F.Fab" user)
		(33 "B.Fab" user)
	)
	(footprint "antmicro-footprints:C_0402_1005Metric"
		(layer "B.Cu")
		(at 175.25 130.776 90)
		(descr "Capacitor SMD 0402")
		(tags "capacitor SMD 0402")
		(property "Reference" "C127"
			(at 2.246 1.38 90)
			(layer "B.SilkS")
			(effects
				(font
					(size 0.7 0.7)
					(thickness 0.15)
				)
				(justify left bottom mirror)
			)
		)
		(property "Value" "C_1u_0402"
			(at -1.022927 -2.155213 270)
			(layer "B.Fab")
			(hide yes)
			(effects
				(font
					(size 0.7 0.7)
					(thickness 0.15)
				)
				(justify left bottom mirror)
			)
		)
		(property "Datasheet" "https://product.tdk.com/en/search/capacitor/ceramic/mlcc/info?part_no=C1005X6S1A105K050BC"
			(at 0 0 90)
			(layer "F.Fab")
			(hide yes)
			(effects
				(font
					(size 1.27 1.27)
					(thickness 0.15)
				)
			)
		)
		(property "Description" "SMD Multilayer Ceramic Capacitor, 1 µF, 10 V, 0402 [1005 Metric], ± 10%, X6S, C"
			(at 0 0 90)
			(layer "F.Fab")
			(hide yes)
			(effects
				(font
					(size 1.27 1.27)
					(thickness 0.15)
				)
			)
		)
		(property "Author" "Antmicro"
			(at 306.026 -44.474 0)
			(layer "B.Fab")
			(hide yes)
			(effects
				(font
					(size 1 1)
					(thickness 0.15)
				)
				(justify mirror)
			)
		)
		(property "Dielectric" "X5R"
			(at 306.026 -44.474 0)
			(layer "B.Fab")
			(hide yes)
			(effects
				(font
					(size 1 1)
					(thickness 0.15)
				)
				(justify mirror)
			)
		)
		(property "License" "Apache-2.0"
			(at 306.026 -44.474 0)
			(layer "B.Fab")
			(hide yes)
			(effects
				(font
					(size 1 1)
					(thickness 0.15)
				)
				(justify mirror)
			)
		)
		(property "MPN" "C1005X6S1A105K050BC"
			(at 306.026 -44.474 0)
			(layer "B.Fab")
			(hide yes)
			(effects
				(font
					(size 1 1)
					(thickness 0.15)
				)
				(justify mirror)
			)
		)
		(property "Manufacturer" "TDK"
			(at 306.026 -44.474 0)
			(layer "B.Fab")
			(hide yes)
			(effects
				(font
					(size 1 1)
					(thickness 0.15)
				)
				(justify mirror)
			)
		)
		(property "Public" ""
			(at 306.026 -44.474 0)
			(layer "B.Fab")
			(hide yes)
			(effects
				(font
					(size 1 1)
					(thickness 0.15)
				)
				(justify mirror)
			)
		)
		(property "Val" "1u"
			(at 306.026 -44.474 0)
			(layer "B.Fab")
			(hide yes)
			(effects
				(font
					(size 1 1)
					(thickness 0.15)
				)
				(justify mirror)
			)
		)
		(property "Voltage" "16V"
			(at 306.026 -44.474 0)
			(layer "B.Fab")
			(hide yes)
			(effects
				(font
					(size 1 1)
					(thickness 0.15)
				)
				(justify mirror)
			)
		)
		(sheetname "/LPDDR4/")
		(sheetfile "lpddr.kicad_sch")
		(attr smd)
		(fp_rect
			(start -0.925 0.47)
			(end 0.925 -0.47)
			(stroke
				(width 0.05)
				(type default)
			)
			(fill no)
			(layer "B.CrtYd")
		)
		(fp_line
			(start 0.504 -0.248)
			(end -0.494 -0.248)
			(stroke
				(width 0.15)
				(type solid)
			)
			(layer "B.Fab")
		)
		(fp_line
			(start -0.494 -0.248)
			(end -0.494 0.25)
			(stroke
				(width 0.15)
				(type solid)
			)
			(layer "B.Fab")
		)
		(fp_line
			(start 0.504 0.25)
			(end 0.504 -0.248)
			(stroke
				(width 0.15)
				(type solid)
			)
			(layer "B.Fab")
		)
		(fp_line
			(start -0.494 0.25)
			(end 0.504 0.25)
			(stroke
				(width 0.15)
				(type solid)
			)
			(layer "B.Fab")
		)
		(fp_text user "${REFERENCE}"
			(at -0.939 -4.599 270)
			(layer "B.Fab")
			(effects
				(font
					(size 0.7 0.7)
					(thickness 0.15)
				)
				(justify left bottom mirror)
			)
		)
		(fp_text user "License: Apache-2.0"
			(at -0.939 -5.799 270)
			(layer "B.Fab")
			(effects
				(font
					(size 0.7 0.7)
					(thickness 0.15)
				)
				(justify left bottom mirror)
			)
		)
		(fp_text user "Author: Antmicro"
			(at -0.939 -3.399 270)
			(layer "B.Fab")
			(effects
				(font
					(size 0.7 0.7)
					(thickness 0.15)
				)
				(justify left bottom mirror)
			)
		)
		(pad "1" smd roundrect
			(at -0.48 0 90)
			(size 0.59 0.64)
			(layers "B.Cu" "B.Mask" "B.Paste")
			(roundrect_rratio 0.25)
			(net 417 "GND")
			(pintype "passive")
		)
		(pad "2" smd roundrect
			(at 0.48 0 90)
			(size 0.59 0.64)
			(layers "B.Cu" "B.Mask" "B.Paste")
			(roundrect_rratio 0.25)
			(net 2 "+1V1")
			(pintype "passive")
		)
	)
	(footprint "antmicro-footprints:C_0402_1005Metric"
		(layer "B.Cu")
		(at 210.9 144.65 90)
		(descr "Capacitor SMD 0402")
		(tags "capacitor SMD 0402")
		(property "Reference" "C177"
			(at 2.075 -0.325 90)
			(layer "B.SilkS")
			(effects
				(font
					(size 0.7 0.7)
					(thickness 0.15)
				)
				(justify right bottom mirror)
			)
		)
		(property "Value" "C_100n_0402"
			(at -1.022927 -2.155213 90)
			(layer "B.Fab")
			(hide yes)
			(effects
				(font
					(size 0.7 0.7)
					(thickness 0.15)
				)
				(justify right bottom mirror)
			)
		)
		(property "Datasheet" "https://www.murata.com/products/productdetail?partno=GRM155R61H104KE14%23"
			(at 0 0 90)
			(layer "F.Fab")
			(hide yes)
			(effects
				(font
					(size 1.27 1.27)
					(thickness 0.15)
				)
			)
		)
		(property "Description" "SMD Multilayer Ceramic Capacitor, 0.1 µF, 50 V, 0402 [1005 Metric], ± 10%, X5R, GRM Series"
			(at 0 0 90)
			(layer "F.Fab")
			(hide yes)
			(effects
				(font
					(size 1.27 1.27)
					(thickness 0.15)
				)
			)
		)
		(property "Author" "Antmicro"
			(at 355.55 -66.25 0)
			(layer "B.Fab")
			(hide yes)
			(effects
				(font
					(size 1 1)
					(thickness 0.15)
				)
				(justify mirror)
			)
		)
		(property "Dielectric" "X5R"
			(at 355.55 -66.25 0)
			(layer "B.Fab")
			(hide yes)
			(effects
				(font
					(size 1 1)
					(thickness 0.15)
				)
				(justify mirror)
			)
		)
		(property "License" "Apache-2.0"
			(at 355.55 -66.25 0)
			(layer "B.Fab")
			(hide yes)
			(effects
				(font
					(size 1 1)
					(thickness 0.15)
				)
				(justify mirror)
			)
		)
		(property "MPN" "GRM155R61H104KE14D"
			(at 355.55 -66.25 0)
			(layer "B.Fab")
			(hide yes)
			(effects
				(font
					(size 1 1)
					(thickness 0.15)
				)
				(justify mirror)
			)
		)
		(property "Manufacturer" "Murata"
			(at 355.55 -66.25 0)
			(layer "B.Fab")
			(hide yes)
			(effects
				(font
					(size 1 1)
					(thickness 0.15)
				)
				(justify mirror)
			)
		)
		(property "Public" ""
			(at 355.55 -66.25 0)
			(layer "B.Fab")
			(hide yes)
			(effects
				(font
					(size 1 1)
					(thickness 0.15)
				)
				(justify mirror)
			)
		)
		(property "Val" "100n"
			(at 355.55 -66.25 0)
			(layer "B.Fab")
			(hide yes)
			(effects
				(font
					(size 1 1)
					(thickness 0.15)
				)
				(justify mirror)
			)
		)
		(property "Voltage" "50V"
			(at 355.55 -66.25 0)
			(layer "B.Fab")
			(hide yes)
			(effects
				(font
					(size 1 1)
					(thickness 0.15)
				)
				(justify mirror)
			)
		)
		(sheetname "/USB/")
		(sheetfile "usb.kicad_sch")
		(attr smd)
		(fp_rect
			(start -0.925 0.47)
			(end 0.925 -0.47)
			(stroke
				(width 0.05)
				(type default)
			)
			(fill no)
			(layer "B.CrtYd")
		)
		(fp_line
			(start 0.504 -0.248)
			(end -0.494 -0.248)
			(stroke
				(width 0.15)
				(type solid)
			)
			(layer "B.Fab")
		)
		(fp_line
			(start -0.494 -0.248)
			(end -0.494 0.25)
			(stroke
				(width 0.15)
				(type solid)
			)
			(layer "B.Fab")
		)
		(fp_line
			(start 0.504 0.25)
			(end 0.504 -0.248)
			(stroke
				(width 0.15)
				(type solid)
			)
			(layer "B.Fab")
		)
		(fp_line
			(start -0.494 0.25)
			(end 0.504 0.25)
			(stroke
				(width 0.15)
				(type solid)
			)
			(layer "B.Fab")
		)
		(fp_text user "Author: Antmicro"
			(at -0.939 -3.399 270)
			(layer "B.Fab")
			(effects
				(font
					(size 0.7 0.7)
					(thickness 0.15)
				)
				(justify left bottom mirror)
			)
		)
		(fp_text user "${REFERENCE}"
			(at -0.939 -4.599 270)
			(layer "B.Fab")
			(effects
				(font
					(size 0.7 0.7)
					(thickness 0.15)
				)
				(justify left bottom mirror)
			)
		)
		(fp_text user "License: Apache-2.0"
			(at -0.939 -5.799 270)
			(layer "B.Fab")
			(effects
				(font
					(size 0.7 0.7)
					(thickness 0.15)
				)
				(justify left bottom mirror)
			)
		)
		(pad "1" smd roundrect
			(at -0.48 0 90)
			(size 0.59 0.64)
			(layers "B.Cu" "B.Mask" "B.Paste")
			(roundrect_rratio 0.25)
			(net 417 "GND")
			(pintype "passive")
		)
		(pad "2" smd roundrect
			(at 0.48 0 90)
			(size 0.59 0.64)
			(layers "B.Cu" "B.Mask" "B.Paste")
			(roundrect_rratio 0.25)
			(net 50 "+3V3")
			(pintype "passive")
		)
	)
	(footprint "antmicro-footprints:L_0603_1608Metric"
		(layer "B.Cu")
		(at 219.2 146.945)
		(property "Reference" "L6"
			(at 6.175 -8.33 0)
			(layer "B.SilkS")
			(effects
				(font
					(size 0.7 0.7)
					(thickness 0.15)
				)
				(justify right bottom mirror)
			)
		)
		(property "Value" "L_2u2_1.2A_0603"
			(at 0 -2 0)
			(layer "B.Fab")
			(hide yes)
			(effects
				(font
					(size 0.7 0.7)
					(thickness 0.15)
				)
				(justify right bottom mirror)
			)
		)
		(property "Datasheet" "https://www.mouser.com/datasheet/2/3/AOTA_B160808S-3224144.pdf"
			(at 0 0 0)
			(layer "F.Fab")
			(hide yes)
			(effects
				(font
					(size 1.27 1.27)
					(thickness 0.15)
				)
			)
		)
		(property "Description" "Wirewound Inductor, 2.2 µH, 240 mOhm, 40 MHz, 1.2 A, 0603 [1608 Metric]"
			(at 0 0 0)
			(layer "F.Fab")
			(hide yes)
			(effects
				(font
					(size 1.27 1.27)
					(thickness 0.15)
				)
			)
		)
		(property "Author" "Antmicro"
			(at 0 0 0)
			(layer "B.Fab")
			(hide yes)
			(effects
				(font
					(size 1 1)
					(thickness 0.15)
				)
				(justify mirror)
			)
		)
		(property "IMax" "1.2 A"
			(at 0 0 0)
			(layer "B.Fab")
			(hide yes)
			(effects
				(font
					(size 1 1)
					(thickness 0.15)
				)
				(justify mirror)
			)
		)
		(property "ISat" "1.3 A"
			(at 0 0 0)
			(layer "B.Fab")
			(hide yes)
			(effects
				(font
					(size 1 1)
					(thickness 0.15)
				)
				(justify mirror)
			)
		)
		(property "License" "Apache-2.0"
			(at 0 0 0)
			(layer "B.Fab")
			(hide yes)
			(effects
				(font
					(size 1 1)
					(thickness 0.15)
				)
				(justify mirror)
			)
		)
		(property "MPN" "AOTA-B160808S2R2MT "
			(at 0 0 0)
			(layer "B.Fab")
			(hide yes)
			(effects
				(font
					(size 1 1)
					(thickness 0.15)
				)
				(justify mirror)
			)
		)
		(property "Manufacturer" "Abracon"
			(at 0 0 0)
			(layer "B.Fab")
			(hide yes)
			(effects
				(font
					(size 1 1)
					(thickness 0.15)
				)
				(justify mirror)
			)
		)
		(property "Public" ""
			(at 0 0 0)
			(layer "B.Fab")
			(hide yes)
			(effects
				(font
					(size 1 1)
					(thickness 0.15)
				)
				(justify mirror)
			)
		)
		(property "Size" "1.6 x 0.8 x 0.8"
			(at 0 0 0)
			(layer "B.Fab")
			(hide yes)
			(effects
				(font
					(size 1 1)
					(thickness 0.15)
				)
				(justify mirror)
			)
		)
		(property "Val" "2u2/1.2A"
			(at 0 0 0)
			(layer "B.Fab")
			(hide yes)
			(effects
				(font
					(size 1 1)
					(thickness 0.15)
				)
				(justify mirror)
			)
		)
		(sheetname "/WiFi_Bluetooth/")
		(sheetfile "wifi_bt.kicad_sch")
		(attr smd)
		(fp_line
			(start -0.15 -0.4)
			(end 0.15 -0.4)
			(stroke
				(width 0.15)
				(type solid)
			)
			(layer "B.SilkS")
		)
		(fp_line
			(start -0.15 0.4)
			(end 0.15 0.4)
			(stroke
				(width 0.15)
				(type solid)
			)
			(layer "B.SilkS")
		)
		(fp_rect
			(start -1.25 0.65)
			(end 1.25 -0.65)
			(stroke
				(width 0.05)
				(type solid)
			)
			(fill no)
			(layer "B.CrtYd")
		)
		(fp_rect
			(start -0.8 0.4)
			(end 0.8 -0.4)
			(stroke
				(width 0.1)
				(type solid)
			)
			(fill no)
			(layer "B.Fab")
		)
		(fp_text user "License: Apache-2.0"
			(at -1.9 -5.75 180)
			(layer "B.Fab")
			(effects
				(font
					(size 0.7 0.7)
					(thickness 0.15)
				)
				(justify left bottom mirror)
			)
		)
		(fp_text user "${REFERENCE}"
			(at -1.9 -3.1 180)
			(layer "B.Fab")
			(effects
				(font
					(size 0.7 0.7)
					(thickness 0.15)
				)
				(justify left bottom mirror)
			)
		)
		(fp_text user "Author: Antmicro"
			(at -1.9 -4.4 180)
			(layer "B.Fab")
			(effects
				(font
					(size 0.7 0.7)
					(thickness 0.15)
				)
				(justify left bottom mirror)
			)
		)
		(pad "1" smd roundrect
			(at -0.7 0)
			(size 0.8 1)
			(layers "B.Cu" "B.Mask" "B.Paste")
			(roundrect_rratio 0.2)
			(net 151 "Net-(U26A-VIN_LDO)")
			(pintype "passive")
		)
		(pad "2" smd roundrect
			(at 0.7 0)
			(size 0.8 1)
			(layers "B.Cu" "B.Mask" "B.Paste")
			(roundrect_rratio 0.2)
			(net 220 "Net-(U26A-SR_VLX)")
			(pintype "passive")
		)
	)
	(footprint "antmicro-footprints:R_0402_1005Metric"
		(layer "B.Cu")
		(at 216.37 147.58 180)
		(descr "Resistor SMD 0402")
		(tags "resistor SMD 0402")
		(property "Reference" "R100"
			(at -2.9 -3.93 0)
			(layer "B.SilkS")
			(effects
				(font
					(size 0.7 0.7)
					(thickness 0.15)
				)
				(justify left bottom mirror)
			)
		)
		(property "Value" "R_100k_0402"
			(at -1.011843 -1.772047 0)
			(layer "B.Fab")
			(hide yes)
			(effects
				(font
					(size 0.7 0.7)
					(thickness 0.15)
				)
				(justify left bottom mirror)
			)
		)
		(property "Datasheet" "https://www.bourns.com/docs/product-datasheets/cr.pdf"
			(at 0 0 180)
			(layer "F.Fab")
			(hide yes)
			(effects
				(font
					(size 1.27 1.27)
					(thickness 0.15)
				)
			)
		)
		(property "Description" "SMD Chip Resistor, 100 kohm, ± 1%, 62.5 mW, 0402 [1005 Metric], Thick Film, General Purpose"
			(at 0 0 180)
			(layer "F.Fab")
			(hide yes)
			(effects
				(font
					(size 1.27 1.27)
					(thickness 0.15)
				)
			)
		)
		(property "Author" "Antmicro"
			(at 432.74 295.16 0)
			(layer "B.Fab")
			(hide yes)
			(effects
				(font
					(size 1 1)
					(thickness 0.15)
				)
				(justify mirror)
			)
		)
		(property "License" "Apache-2.0"
			(at 432.74 295.16 0)
			(layer "B.Fab")
			(hide yes)
			(effects
				(font
					(size 1 1)
					(thickness 0.15)
				)
				(justify mirror)
			)
		)
		(property "MPN" "CR0402-FX-1003GLF"
			(at 432.74 295.16 0)
			(layer "B.Fab")
			(hide yes)
			(effects
				(font
					(size 1 1)
					(thickness 0.15)
				)
				(justify mirror)
			)
		)
		(property "Manufacturer" "Bourns"
			(at 432.74 295.16 0)
			(layer "B.Fab")
			(hide yes)
			(effects
				(font
					(size 1 1)
					(thickness 0.15)
				)
				(justify mirror)
			)
		)
		(property "Public" ""
			(at 432.74 295.16 0)
			(layer "B.Fab")
			(hide yes)
			(effects
				(font
					(size 1 1)
					(thickness 0.15)
				)
				(justify mirror)
			)
		)
		(property "Tolerance" "1%"
			(at 432.74 295.16 0)
			(layer "B.Fab")
			(hide yes)
			(effects
				(font
					(size 1 1)
					(thickness 0.15)
				)
				(justify mirror)
			)
		)
		(property "Val" "100k"
			(at 432.74 295.16 0)
			(layer "B.Fab")
			(hide yes)
			(effects
				(font
					(size 1 1)
					(thickness 0.15)
				)
				(justify mirror)
			)
		)
		(sheetname "/USB/")
		(sheetfile "usb.kicad_sch")
		(attr smd)
		(fp_rect
			(start -0.925 0.47)
			(end 0.925 -0.47)
			(stroke
				(width 0.05)
				(type default)
			)
			(fill no)
			(layer "B.CrtYd")
		)
		(fp_rect
			(start -0.5 0.25)
			(end 0.5 -0.25)
			(stroke
				(width 0.15)
				(type solid)
			)
			(fill no)
			(layer "B.Fab")
		)
		(fp_text user "Author: Antmicro"
			(at -0.95 -4.169 0)
			(layer "B.Fab")
			(effects
				(font
					(size 0.7 0.7)
					(thickness 0.15)
				)
				(justify left bottom mirror)
			)
		)
		(fp_text user "${REFERENCE}"
			(at -0.95 -3.168 0)
			(layer "B.Fab")
			(effects
				(font
					(size 0.7 0.7)
					(thickness 0.15)
				)
				(justify left bottom mirror)
			)
		)
		(fp_text user "License: Apache-2.0"
			(at -0.95 -5.169 0)
			(layer "B.Fab")
			(effects
				(font
					(size 0.7 0.7)
					(thickness 0.15)
				)
				(justify left bottom mirror)
			)
		)
		(pad "1" smd roundrect
			(at -0.48 0 180)
			(size 0.59 0.64)
			(layers "B.Cu" "B.Mask" "B.Paste")
			(roundrect_rratio 0.25)
			(net 318 "Net-(U28-SUSP_IND)")
			(pintype "passive")
		)
		(pad "2" smd roundrect
			(at 0.48 0 180)
			(size 0.59 0.64)
			(layers "B.Cu" "B.Mask" "B.Paste")
			(roundrect_rratio 0.25)
			(net 50 "+3V3")
			(pintype "passive")
		)
	)
)
